#ISCELL
  mstr_misc dns *
  *
#ISCELL
  pure_quanta quanta_title_block_c *
  *
#ISCELL
  logical_power universal_gnd *
  page262_i1
#CELL
  pure_quanta q_cap *
  page262_i10
#ISCELL
  logical_power universal_gnd *
  page262_i11
#CELL
  pure_quanta q_cap *
  page262_i12
#CELL
  pure_quanta q_res *
  page262_i13
#CELL
  pure_quanta raa2213404gnphb0 *
  page262_i14
#CELL
  pure_quanta q_res *
  page262_i15
#CELL
  pure_quanta q_res *
  page262_i16
#CELL
  pure_quanta q_res *
  page262_i17
#ISCELL
  logical_power universal_gnd *
  page262_i18
#ISCELL
  logical_power vcc15 *
  page262_i19
#CELL
  pure_quanta q_res *
  page262_i2
#CELL
  pure_quanta q_cap *
  page262_i20
#CELL
  pure_quanta q_res *
  page262_i21
#CELL
  pure_quanta q_res *
  page262_i22
#ISCELL
  logical_power vcc15 *
  page262_i23
#CELL
  pure_quanta q_cap *
  page262_i24
#CELL
  pure_quanta q_cap *
  page262_i25
#CELL
  pure_quanta q_cap *
  page262_i26
#CELL
  pure_quanta q_cap *
  page262_i27
#CELL
  pure_quanta q_cap *
  page262_i28
#CELL
  pure_quanta q_inductor *
  page262_i29
#ISCELL
  standard offpage *
  page262_i3
#ISCELL
  logical_power universal_gnd *
  page262_i30
#CELL
  pure_quanta q_cap *
  page262_i31
#CELL
  pure_quanta q_cap *
  page262_i32
#CELL
  pure_quanta q_capp *
  page262_i33
#CELL
  pure_quanta q_capp *
  page262_i34
#ISCELL
  logical_power universal_gnd *
  page262_i35
#CELL
  pure_quanta q_res *
  page262_i36
#ISCELL
  logical_power vcc15 *
  page262_i37
#ISCELL
  logical_power vcc15 *
  page262_i38
#ISCELL
  standard offpage *
  page262_i4
#ISCELL
  logical_power universal_gnd *
  page262_i5
#ISCELL
  standard offpage *
  page262_i6
#ISCELL
  standard offpage *
  page262_i7
#CELL
  pure_quanta q_res *
  page262_i8
#ISCELL
  logical_power vcc15 *
  page262_i9
